# T6G (Grand Teton) — schematic netlist excerpt (pin names and nets, part order shuffled) for the footprints in the layout excerpt that follows; sources: Cadence DE-HDL packaged netlist, KiCad conversion of 04192023_DAF0TMB3IC0_F0TG_MB_C_brd_V02_OCP.brd

H77  HOLE  EMPTY  pkg TH  page 230 : \1\ = GND
PC6645  Q_CAP  2.2UF 10V 10% X6S  pkg C0402  page 365 : A = P0V9_RETIMER_CPU1_VCC2 ; B = GND

(kicad_pcb
	(version 20260206)
	(generator "pcbnew")
	(generator_version "10.0")
	(general
		(thickness 1.6)
		(legacy_teardrops no)
	)
	(paper "A4")
	(title_block
		(title "04192023_DAF0TMB3IC0_F0TG_MB_C_brd_V02_OCP.brd")
		(comment 1 "Grand Teton / footprints 2713-2714 of 8354")
	)
	(layers
		(0 "F.Cu" signal "TOP")
		(4 "In1.Cu" signal "GND")
		(6 "In2.Cu" signal "IN1")
		(8 "In3.Cu" signal "GND1")
		(10 "In4.Cu" signal "IN2")
		(12 "In5.Cu" signal "GND2")
		(14 "In6.Cu" signal "IN3")
		(16 "In7.Cu" signal "GND3")
		(18 "In8.Cu" signal "VCC")
		(20 "In9.Cu" signal "VCC1")
		(22 "In10.Cu" signal "GND4")
		(24 "In11.Cu" signal "IN4")
		(26 "In12.Cu" signal "GND5")
		(28 "In13.Cu" signal "IN5")
		(30 "In14.Cu" signal "GND6")
		(32 "In15.Cu" signal "IN6")
		(34 "In16.Cu" signal "GND7")
		(2 "B.Cu" signal "BOTTOM")
		(9 "F.Adhes" user "F.Adhesive")
		(11 "B.Adhes" user "B.Adhesive")
		(13 "F.Paste" user "Package Geometry/Pastemask Top")
		(15 "B.Paste" user "Package Geometry/Pastemask Bottom")
		(5 "F.SilkS" user "Ref Des/Silkscreen Top")
		(7 "B.SilkS" user "Ref Des/Silkscreen Bottom")
		(1 "F.Mask" user "Board Geometry/Soldermask Top")
		(3 "B.Mask" user "Board Geometry/Soldermask Bottom")
		(17 "Dwgs.User" user "User.Drawings")
		(19 "Cmts.User" user "User.Comments")
		(21 "Eco1.User" user "User.Eco1")
		(23 "Eco2.User" user "User.Eco2")
		(25 "Edge.Cuts" user "Board Geometry/Outline")
		(27 "Margin" user)
		(31 "F.CrtYd" user "Package Geometry/Place Bound Top")
		(29 "B.CrtYd" user "Package Geometry/Place Bound Bottom")
		(35 "F.Fab" user "Ref Des/Assembly Top")
		(33 "B.Fab" user "Ref Des/Assembly Bottom")
	)
	(footprint ""
		(layer "F.Cu")
		(at 21.938996 -390.949434 90)
		(property "Reference" "PC6645"
			(at 0 0 90)
			(layer "F.SilkS")
			(hide yes)
			(effects
				(font
					(size 1.27 1.27)
				)
			)
		)
		(property "Value" ""
			(at 0 0 90)
			(layer "F.Fab")
			(effects
				(font
					(size 1.27 1.27)
				)
			)
		)
		(duplicate_pad_numbers_are_jumpers no)
		(fp_line
			(start 0.7874 -0.4064)
			(end 0.7874 -0.221996)
			(stroke
				(width 0.1524)
				(type default)
			)
			(layer "F.SilkS")
		)
		(fp_line
			(start -0.7874 -0.4064)
			(end 0.7874 -0.4064)
			(stroke
				(width 0.1524)
				(type default)
			)
			(layer "F.SilkS")
		)
		(fp_line
			(start 0.464566 0.4064)
			(end -0.7874 0.4064)
			(stroke
				(width 0.1524)
				(type default)
			)
			(layer "F.SilkS")
		)
		(fp_line
			(start -0.7874 0.4064)
			(end -0.7874 -0.4064)
			(stroke
				(width 0.1524)
				(type default)
			)
			(layer "F.SilkS")
		)
		(fp_line
			(start -0.12065 -0.305054)
			(end -0.12065 -0.2794)
			(stroke
				(width 0.1)
				(type default)
			)
			(layer "F.Fab")
		)
		(fp_line
			(start -0.67945 -0.305054)
			(end -0.12065 -0.305054)
			(stroke
				(width 0.1)
				(type default)
			)
			(layer "F.Fab")
		)
		(fp_line
			(start 0.67945 -0.3048)
			(end 0.67945 0.3048)
			(stroke
				(width 0.1)
				(type default)
			)
			(layer "F.Fab")
		)
		(fp_line
			(start 0.12065 -0.3048)
			(end 0.67945 -0.3048)
			(stroke
				(width 0.1)
				(type default)
			)
			(layer "F.Fab")
		)
		(fp_line
			(start 0.12065 -0.2794)
			(end 0.12065 -0.3048)
			(stroke
				(width 0.1)
				(type default)
			)
			(layer "F.Fab")
		)
		(fp_line
			(start -0.12065 -0.2794)
			(end 0.12065 -0.2794)
			(stroke
				(width 0.1)
				(type default)
			)
			(layer "F.Fab")
		)
		(fp_line
			(start 0.120396 0.2794)
			(end -0.12065 0.2794)
			(stroke
				(width 0.1)
				(type default)
			)
			(layer "F.Fab")
		)
		(fp_line
			(start -0.12065 0.2794)
			(end -0.12065 0.3048)
			(stroke
				(width 0.1)
				(type default)
			)
			(layer "F.Fab")
		)
		(fp_line
			(start 0.67945 0.3048)
			(end 0.120396 0.3048)
			(stroke
				(width 0.1)
				(type default)
			)
			(layer "F.Fab")
		)
		(fp_line
			(start 0.120396 0.3048)
			(end 0.120396 0.2794)
			(stroke
				(width 0.1)
				(type default)
			)
			(layer "F.Fab")
		)
		(fp_line
			(start -0.12065 0.3048)
			(end -0.67945 0.3048)
			(stroke
				(width 0.1)
				(type default)
			)
			(layer "F.Fab")
		)
		(fp_line
			(start -0.67945 0.3048)
			(end -0.67945 -0.305054)
			(stroke
				(width 0.1)
				(type default)
			)
			(layer "F.Fab")
		)
		(pad "1" smd circle
			(at -0.40005 0 90)
			(size 0 0)
			(layers "F.Cu" "F.Mask" "F.Paste")
			(net "P0V9_RETIMER_CPU1_VCC2")
		)
		(pad "2" smd circle
			(at 0.40005 0 90)
			(size 0 0)
			(layers "F.Cu" "F.Mask" "F.Paste")
			(net "GND")
		)
	)
	(footprint ""
		(layer "F.Cu")
		(at 228.650038 -44.494958)
		(property "Reference" "H77"
			(at -1.143 -3.266948 0)
			(unlocked yes)
			(layer "B.SilkS")
			(effects
				(font
					(size 0.7874 0.5842)
					(thickness 0.1524)
				)
				(justify left mirror)
			)
		)
		(property "Value" ""
			(at 0 0 0)
			(layer "F.Fab")
			(effects
				(font
					(size 1.27 1.27)
				)
			)
		)
		(duplicate_pad_numbers_are_jumpers no)
		(pad "1" thru_hole rect
			(at 0 0)
			(size 4.2164 5.0038)
			(drill 2.0066
				(offset 0.099822 0)
			)
			(layers "*.Cu" "*.Mask")
			(remove_unused_layers no)
			(net "GND")
			(clearance -0.8509)
			(padstack
				(mode front_inner_back)
				(layer "Inner"
					(shape circle)
					(size 4.0132 4.0132)
					(clearance -0.7493)
				)
				(layer "B.Cu"
					(shape circle)
					(size 4.0132 4.0132)
					(clearance -0.7493)
				)
			)
		)
	)
)
